FILE_TYPE = CONNECTIVITY;
{Allegro Design Entry HDL 17.4-2019 S026 (4007227) 1/17/2022}
"PAGE_NUMBER" = 398;
0"NC";
1"P1V8_CPU1_RT_1D\g";
2"GND\g";
3"P1V8_CPU1_RT0_1A\g";
4"GND\g";
5"P0V9_CPU1_RT0_2A\g";
6"GND\g";
7"P0V9_CPU1_RT_2D\g";
8"GND\g";
9"GND\g";
10"GND\g";
11"P0V9_CPU1_RT0_2A_2D\g";
12"P1V8_CPU1_RT0_1A_1D\g";
13"GND\g";
%"P1V0"
"1","(-8425,5575)","0","pure_quanta_power","I1";
;
HDL_POWER"P1V8_CPU1_RT_1D"
CDS_LIB"pure_quanta_power";
"A"1;
%"UNIVERSAL_GND"
"1","(-6425,4150)","0","pure_quanta_power","I10";
;
CDS_LIB"pure_quanta_power"
HDL_POWER"GND";
"A"4;
%"Q_CAP"
"1","(-2500,1425)","0","pure_quanta","I100";
;
LOCATION"C201"
$SEC"1"
CDS_SEC"1"
VALUE"1UF"
VOLTAGE"4V"
PACK_TYPE"0201"
MATERIAL"X6S"
TOLERANCE"20%"
CDS_LIB"pure_quanta"
PART_NUMBER"CH-10KMEE00";
"B"
$PN"2"10;
"A"
$PN"1"11;
%"Q_CAP"
"1","(-2125,3200)","0","pure_quanta","I101";
;
LOCATION"C281"
$SEC"1"
CDS_SEC"1"
TOLERANCE"10%"
PACK_TYPE"C0201"
MATERIAL"X7S"
VALUE"0.1UF"
VOLTAGE"10V"
CDS_LIB"pure_quanta"
PART_NUMBER"CH4102K6E00";
"B"
$PN"2"6;
"A"
$PN"1"5;
%"Q_CAP"
"1","(-1875,3200)","0","pure_quanta","I102";
;
LOCATION"C283"
$SEC"1"
CDS_SEC"1"
MATERIAL"X7S"
PACK_TYPE"C0201"
VOLTAGE"10V"
VALUE"0.1UF"
TOLERANCE"10%"
CDS_LIB"pure_quanta"
PART_NUMBER"CH4102K6E00";
"B"
$PN"2"6;
"A"
$PN"1"5;
%"Q_CAPP"
"1","(-1350,2550)","0","pure_quanta","I103";
;
LOCATION"C7020"
$SEC"1"
CDS_SEC"1"
MATERIAL"SPCAP"
VOLTAGE"2.5V"
PACK_TYPE"SMLF"
TOLERANCE"20%"
VALUE"470UF"
CDS_LIB"pure_quanta"
PART_NUMBER"CH747LM8818";
"A"
$PN"1"5;
"B"
$PN"2"9;
%"Q_CAPP"
"1","(-1050,2550)","0","pure_quanta","I104";
;
LOCATION"C7021"
$SEC"1"
CDS_SEC"1"
VALUE"470UF"
TOLERANCE"20%"
MATERIAL"SPCAP"
PACK_TYPE"SMLF"
VOLTAGE"2.5V"
CDS_LIB"pure_quanta"
PART_NUMBER"CH747LM8818";
"A"
$PN"1"5;
"B"
$PN"2"9;
%"Q_CAP"
"1","(-750,2550)","0","pure_quanta","I105";
;
LOCATION"C7022"
$SEC"1"
CDS_SEC"1"
TOLERANCE"20%"
MATERIAL"X6S"
PACK_TYPE"C0805"
VALUE"100UF"
VOLTAGE"4V"
CDS_LIB"pure_quanta"
PART_NUMBER"CH710KMEA01";
"B"
$PN"2"9;
"A"
$PN"1"5;
%"Q_CAP"
"1","(-7325,5300)","0","pure_quanta","I12";
;
LOCATION"C113"
$SEC"1"
CDS_SEC"1"
PACK_TYPE"C0805"
VOLTAGE"4V"
MATERIAL"X6S"
VALUE"100UF"
TOLERANCE"20%"
CDS_LIB"pure_quanta"
PART_NUMBER"CH710KMEA01";
"B"
$PN"2"2;
"A"
$PN"1"1;
%"Q_CAP"
"1","(-6825,5275)","0","pure_quanta","I14";
;
LOCATION"C118"
$SEC"1"
CDS_SEC"1"
VALUE"10UF"
TOLERANCE"20%"
MATERIAL"X6S"
VOLTAGE"6.3V"
PACK_TYPE"C0402"
CDS_LIB"pure_quanta"
PART_NUMBER"CH6101MEB01";
"B"
$PN"2"2;
"A"
$PN"1"1;
%"Q_CAP"
"1","(-6575,5275)","0","pure_quanta","I15";
;
LOCATION"C122"
$SEC"1"
CDS_SEC"1"
VOLTAGE"6.3V"
VALUE"4.7UF"
TOLERANCE"20%"
MATERIAL"X6S"
PACK_TYPE"0402"
CDS_LIB"pure_quanta"
PART_NUMBER"CH5471MEB01";
"B"
$PN"2"2;
"A"
$PN"1"1;
%"UNIVERSAL_GND"
"1","(-6650,5000)","0","pure_quanta_power","I17";
;
CDS_LIB"pure_quanta_power"
HDL_POWER"GND";
"A"2;
%"Q_CAP"
"1","(-6625,4475)","0","pure_quanta","I18";
;
LOCATION"C123"
$SEC"1"
CDS_SEC"1"
PACK_TYPE"0201"
TOLERANCE"20%"
VALUE"1UF"
MATERIAL"X6S"
VOLTAGE"4V"
CDS_LIB"pure_quanta"
PART_NUMBER"CH-10KMEE00";
"B"
$PN"2"4;
"A"
$PN"1"3;
%"Q_CAP"
"1","(-7050,3400)","0","pure_quanta","I19";
;
LOCATION"C125"
$SEC"1"
CDS_SEC"1"
VOLTAGE"4V"
TOLERANCE"20%"
VALUE"1UF"
MATERIAL"X6S"
PACK_TYPE"0201"
CDS_LIB"pure_quanta"
PART_NUMBER"CH-10KMEE00";
"B"
$PN"2"13;
"A"
$PN"1"12;
%"Q_CAP"
"1","(-7050,4475)","0","pure_quanta","I20";
;
LOCATION"C119"
$SEC"1"
CDS_SEC"1"
MATERIAL"X6S"
TOLERANCE"20%"
PACK_TYPE"C0402"
VALUE"10UF"
VOLTAGE"6.3V"
CDS_LIB"pure_quanta"
PART_NUMBER"CH6101MEB01";
"B"
$PN"2"4;
"A"
$PN"1"3;
%"Q_CAP"
"1","(-7075,5300)","0","pure_quanta","I21";
;
LOCATION"C115"
$SEC"1"
CDS_SEC"1"
VALUE"22UF"
MATERIAL"X6S"
PACK_TYPE"C0402"
VOLTAGE"4V"
TOLERANCE"20%"
CDS_LIB"pure_quanta"
PART_NUMBER"CH622KMEB02";
"B"
$PN"2"2;
"A"
$PN"1"1;
%"Q_INDUCTOR"
"1","(-8050,4750)","0","pure_quanta","I22";
;
LOCATION"L3"
$SEC"1"
CDS_SEC"1"
VALUE"BLM21SN300SN1D/5A"
PACK_TYPE"SMLF"
MATERIAL"IND"
CDS_LIB"pure_quanta"
NEEDS_NO_SIZE"TRUE"
PART_NUMBER"CX300SN1000";
"1"
$PN"1"1;
"2"
$PN"2"3;
%"Q_CAP"
"1","(-6200,4475)","0","pure_quanta","I23";
;
LOCATION"C129"
$SEC"1"
CDS_SEC"1"
TOLERANCE"10%"
VOLTAGE"10V"
VALUE"0.1UF"
PACK_TYPE"C0201"
MATERIAL"X7S"
CDS_LIB"pure_quanta"
PART_NUMBER"CH4102K6E00";
"B"
$PN"2"4;
"A"
$PN"1"3;
%"Q_CAP"
"1","(-5950,4475)","0","pure_quanta","I24";
;
LOCATION"C131"
$SEC"1"
CDS_SEC"1"
PACK_TYPE"C0201"
MATERIAL"X7S"
VALUE"0.1UF"
VOLTAGE"10V"
TOLERANCE"10%"
CDS_LIB"pure_quanta"
PART_NUMBER"CH4102K6E00";
"B"
$PN"2"4;
"A"
$PN"1"3;
%"Q_CAP"
"1","(-5700,4475)","0","pure_quanta","I25";
;
LOCATION"C133"
$SEC"1"
CDS_SEC"1"
MATERIAL"X7S"
TOLERANCE"10%"
VALUE"0.1UF"
VOLTAGE"10V"
PACK_TYPE"C0201"
CDS_LIB"pure_quanta"
PART_NUMBER"CH4102K6E00";
"B"
$PN"2"4;
"A"
$PN"1"3;
%"Q_CAP"
"1","(-5425,4475)","0","pure_quanta","I26";
;
LOCATION"C134"
$SEC"1"
CDS_SEC"1"
MATERIAL"X7S"
PACK_TYPE"C0201"
VOLTAGE"10V"
VALUE"0.1UF"
TOLERANCE"10%"
CDS_LIB"pure_quanta"
PART_NUMBER"CH4102K6E00";
"B"
$PN"2"4;
"A"
$PN"1"3;
%"Q_CAP"
"1","(-6775,3375)","0","pure_quanta","I27";
;
LOCATION"C130"
$SEC"1"
CDS_SEC"1"
PACK_TYPE"C0201"
MATERIAL"X7S"
VOLTAGE"10V"
VALUE"0.1UF"
TOLERANCE"10%"
CDS_LIB"pure_quanta"
PART_NUMBER"CH4102K6E00";
"B"
$PN"2"13;
"A"
$PN"1"12;
%"UNIVERSAL_GND"
"1","(-6775,2975)","0","pure_quanta_power","I28";
;
CDS_LIB"pure_quanta_power"
HDL_POWER"GND";
"A"13;
%"P1V0"
"1","(-7175,3775)","0","pure_quanta_power","I29";
;
HDL_POWER"P1V8_CPU1_RT0_1A_1D"
CDS_LIB"pure_quanta_power";
"A"12;
%"P1V0"
"1","(-7575,4950)","0","pure_quanta_power","I3";
;
HDL_POWER"P1V8_CPU1_RT0_1A"
CDS_LIB"pure_quanta_power";
"A"3;
%"Q_RES"
"1","(-7975,4050)","0","pure_quanta","I32";
;
LOCATION"R6702"
SEC"1"
WATTAGE"1/16W"
PACK_TYPE"0402LF"
TOLERANCE"5%"
VALUE"0"
MATERIAL"EMPTY"
SEC_TYPE"0402LF"
CDS_LIB"pure_quanta"
PART_NUMBER"CS00002JB13";
"B"
$PN"2"3;
"A"
$PN"1"12;
%"Q_RES"
"1","(-7975,3850)","0","pure_quanta","I33";
;
LOCATION"R6703"
SEC"1"
PACK_TYPE"0402LF"
WATTAGE"1/16W"
MATERIAL"EMPTY"
TOLERANCE"5%"
VALUE"0"
CDS_LIB"pure_quanta"
SEC_TYPE"0402LF"
PART_NUMBER"CS00002JB13";
"B"
$PN"2"3;
"A"
$PN"1"12;
%"Q_CAP"
"1","(-3700,5750)","0","pure_quanta","I34";
;
LOCATION"C229"
$SEC"1"
CDS_SEC"1"
MATERIAL"X6S"
PACK_TYPE"C0805"
VOLTAGE"4V"
VALUE"100UF"
TOLERANCE"20%"
CDS_LIB"pure_quanta"
PART_NUMBER"CH710KMEA01";
"B"
$PN"2"8;
"A"
$PN"1"7;
%"Q_CAP"
"1","(-3425,5750)","0","pure_quanta","I35";
;
LOCATION"C244"
$SEC"1"
CDS_SEC"1"
MATERIAL"X6S"
PACK_TYPE"C0402"
VALUE"22UF"
VOLTAGE"4V"
TOLERANCE"20%"
CDS_LIB"pure_quanta"
PART_NUMBER"CH622KMEB02";
"B"
$PN"2"8;
"A"
$PN"1"7;
%"Q_CAP"
"1","(-3100,5725)","0","pure_quanta","I36";
;
LOCATION"C261"
$SEC"1"
CDS_SEC"1"
VOLTAGE"6.3V"
MATERIAL"X6S"
PACK_TYPE"C0402"
VALUE"10UF"
TOLERANCE"20%"
CDS_LIB"pure_quanta"
PART_NUMBER"CH6101MEB01";
"B"
$PN"2"8;
"A"
$PN"1"7;
%"VCC_CORE"
"1","(-4575,6250)","0","pure_quanta_power","I37";
;
HDL_POWER"P0V9_CPU1_RT_2D"
CDS_LIB"pure_quanta_power";
"A"7;
%"Q_CAP"
"1","(-2800,5725)","0","pure_quanta","I39";
;
LOCATION"C256"
$SEC"1"
CDS_SEC"1"
VALUE"4.7UF"
VOLTAGE"6.3V"
TOLERANCE"20%"
MATERIAL"X6S"
PACK_TYPE"0402"
CDS_LIB"pure_quanta"
PART_NUMBER"CH5471MEB01";
"B"
$PN"2"8;
"A"
$PN"1"7;
%"Q_CAP"
"1","(-7475,4475)","0","pure_quanta","I4";
;
LOCATION"C114"
$SEC"1"
CDS_SEC"1"
PACK_TYPE"C0805"
VOLTAGE"4V"
VALUE"100UF"
TOLERANCE"20%"
MATERIAL"X6S"
CDS_LIB"pure_quanta"
PART_NUMBER"CH710KMEA01";
"B"
$PN"2"4;
"A"
$PN"1"3;
%"Q_CAP"
"1","(-2500,5725)","0","pure_quanta","I40";
;
LOCATION"C185"
$SEC"1"
CDS_SEC"1"
MATERIAL"X6S"
PACK_TYPE"0201"
TOLERANCE"20%"
VALUE"1UF"
VOLTAGE"4V"
CDS_LIB"pure_quanta"
PART_NUMBER"CH-10KMEE00";
"B"
$PN"2"8;
"A"
$PN"1"7;
%"UNIVERSAL_GND"
"1","(-1150,2800)","0","pure_quanta_power","I41";
;
CDS_LIB"pure_quanta_power"
HDL_POWER"GND";
"A"6;
%"Q_CAP"
"1","(-3750,3225)","0","pure_quanta","I42";
;
LOCATION"C222"
$SEC"1"
CDS_SEC"1"
TOLERANCE"20%"
VOLTAGE"4V"
PACK_TYPE"0201"
MATERIAL"X6S"
VALUE"1UF"
CDS_LIB"pure_quanta"
PART_NUMBER"CH-10KMEE00";
"B"
$PN"2"6;
"A"
$PN"1"5;
%"Q_CAP"
"1","(-3750,4475)","0","pure_quanta","I44";
;
LOCATION"C220"
$SEC"1"
CDS_SEC"1"
MATERIAL"X6S"
PACK_TYPE"C0805"
TOLERANCE"20%"
VOLTAGE"4V"
VALUE"100UF"
CDS_LIB"pure_quanta"
PART_NUMBER"CH710KMEA01";
"B"
$PN"2"6;
"A"
$PN"1"5;
%"Q_CAP"
"1","(-3525,3225)","0","pure_quanta","I46";
;
LOCATION"C135"
$SEC"1"
CDS_SEC"1"
VOLTAGE"4V"
TOLERANCE"20%"
MATERIAL"X6S"
VALUE"1UF"
PACK_TYPE"0201"
CDS_LIB"pure_quanta"
PART_NUMBER"CH-10KMEE00";
"B"
$PN"2"6;
"A"
$PN"1"5;
%"Q_CAP"
"1","(-3275,3225)","0","pure_quanta","I47";
;
LOCATION"C243"
$SEC"1"
CDS_SEC"1"
PACK_TYPE"0201"
MATERIAL"X6S"
VALUE"1UF"
TOLERANCE"20%"
VOLTAGE"4V"
CDS_LIB"pure_quanta"
PART_NUMBER"CH-10KMEE00";
"B"
$PN"2"6;
"A"
$PN"1"5;
%"Q_CAP"
"1","(-3050,3225)","0","pure_quanta","I48";
;
LOCATION"C138"
$SEC"1"
CDS_SEC"1"
PACK_TYPE"0201"
MATERIAL"X6S"
VALUE"1UF"
TOLERANCE"20%"
VOLTAGE"4V"
CDS_LIB"pure_quanta"
PART_NUMBER"CH-10KMEE00";
"B"
$PN"2"6;
"A"
$PN"1"5;
%"Q_CAP"
"1","(-2800,3225)","0","pure_quanta","I49";
;
LOCATION"C257"
$SEC"1"
CDS_SEC"1"
VALUE"1UF"
VOLTAGE"4V"
PACK_TYPE"0201"
MATERIAL"X6S"
TOLERANCE"20%"
CDS_LIB"pure_quanta"
PART_NUMBER"CH-10KMEE00";
"B"
$PN"2"6;
"A"
$PN"1"5;
%"Q_CAP"
"1","(-7250,4475)","0","pure_quanta","I5";
;
LOCATION"C117"
$SEC"1"
CDS_SEC"1"
VALUE"22UF"
TOLERANCE"20%"
MATERIAL"X6S"
VOLTAGE"4V"
PACK_TYPE"C0402"
CDS_LIB"pure_quanta"
PART_NUMBER"CH622KMEB02";
"B"
$PN"2"4;
"A"
$PN"1"3;
%"Q_CAP"
"1","(-3075,3850)","0","pure_quanta","I50";
;
LOCATION"C221"
$SEC"1"
CDS_SEC"1"
PACK_TYPE"0402"
VOLTAGE"6.3V"
TOLERANCE"20%"
MATERIAL"X6S"
VALUE"4.7UF"
CDS_LIB"pure_quanta"
PART_NUMBER"CH5471MEB01";
"B"
$PN"2"6;
"A"
$PN"1"5;
%"Q_CAP"
"1","(-2825,3850)","0","pure_quanta","I51";
;
LOCATION"C258"
$SEC"1"
CDS_SEC"1"
PACK_TYPE"0402"
VOLTAGE"6.3V"
TOLERANCE"20%"
VALUE"4.7UF"
MATERIAL"X6S"
CDS_LIB"pure_quanta"
PART_NUMBER"CH5471MEB01";
"B"
$PN"2"6;
"A"
$PN"1"5;
%"Q_CAP"
"1","(-3525,4475)","0","pure_quanta","I52";
;
LOCATION"C225"
$SEC"1"
CDS_SEC"1"
VALUE"100UF"
VOLTAGE"4V"
TOLERANCE"20%"
MATERIAL"X6S"
PACK_TYPE"C0805"
CDS_LIB"pure_quanta"
PART_NUMBER"CH710KMEA01";
"B"
$PN"2"6;
"A"
$PN"1"5;
%"Q_CAP"
"1","(-3300,4475)","0","pure_quanta","I53";
;
LOCATION"C240"
$SEC"1"
CDS_SEC"1"
VALUE"100UF"
VOLTAGE"4V"
TOLERANCE"20%"
MATERIAL"X6S"
PACK_TYPE"C0805"
CDS_LIB"pure_quanta"
PART_NUMBER"CH710KMEA01";
"B"
$PN"2"6;
"A"
$PN"1"5;
%"Q_CAP"
"1","(-2825,4475)","0","pure_quanta","I54";
;
LOCATION"C284"
$SEC"1"
CDS_SEC"1"
TOLERANCE"20%"
VOLTAGE"4V"
MATERIAL"X6S"
VALUE"22UF"
PACK_TYPE"C0402"
CDS_LIB"pure_quanta"
PART_NUMBER"CH622KMEB02";
"B"
$PN"2"6;
"A"
$PN"1"5;
%"Q_CAP"
"1","(-2575,3200)","0","pure_quanta","I55";
;
LOCATION"C188"
$SEC"1"
CDS_SEC"1"
VOLTAGE"4V"
TOLERANCE"20%"
VALUE"1UF"
MATERIAL"X6S"
PACK_TYPE"0201"
CDS_LIB"pure_quanta"
PART_NUMBER"CH-10KMEE00";
"B"
$PN"2"6;
"A"
$PN"1"5;
%"Q_CAP"
"1","(-2350,3200)","0","pure_quanta","I56";
;
LOCATION"C265"
$SEC"1"
CDS_SEC"1"
PACK_TYPE"0201"
TOLERANCE"20%"
VOLTAGE"4V"
VALUE"1UF"
MATERIAL"X6S"
CDS_LIB"pure_quanta"
PART_NUMBER"CH-10KMEE00";
"B"
$PN"2"6;
"A"
$PN"1"5;
%"Q_CAP"
"1","(-2600,3850)","0","pure_quanta","I57";
;
LOCATION"C227"
$SEC"1"
CDS_SEC"1"
PACK_TYPE"0402"
MATERIAL"X6S"
VOLTAGE"6.3V"
TOLERANCE"20%"
VALUE"4.7UF"
CDS_LIB"pure_quanta"
PART_NUMBER"CH5471MEB01";
"B"
$PN"2"6;
"A"
$PN"1"5;
%"Q_CAP"
"1","(-2375,3850)","0","pure_quanta","I58";
;
LOCATION"C186"
$SEC"1"
CDS_SEC"1"
MATERIAL"X6S"
VALUE"1UF"
VOLTAGE"4V"
PACK_TYPE"0201"
TOLERANCE"20%"
CDS_LIB"pure_quanta"
PART_NUMBER"CH-10KMEE00";
"B"
$PN"2"6;
"A"
$PN"1"5;
%"Q_CAP"
"1","(-2150,3850)","0","pure_quanta","I59";
;
LOCATION"C280"
$SEC"1"
CDS_SEC"1"
VOLTAGE"4V"
TOLERANCE"20%"
MATERIAL"X6S"
VALUE"1UF"
PACK_TYPE"0201"
CDS_LIB"pure_quanta"
PART_NUMBER"CH-10KMEE00";
"B"
$PN"2"6;
"A"
$PN"1"5;
%"Q_CAP"
"1","(-1925,3850)","0","pure_quanta","I62";
;
LOCATION"C190"
$SEC"1"
CDS_SEC"1"
VOLTAGE"4V"
TOLERANCE"20%"
VALUE"1UF"
MATERIAL"X6S"
PACK_TYPE"0201"
CDS_LIB"pure_quanta"
PART_NUMBER"CH-10KMEE00";
"B"
$PN"2"6;
"A"
$PN"1"5;
%"Q_CAP"
"1","(-1675,3850)","0","pure_quanta","I63";
;
LOCATION"C285"
$SEC"1"
CDS_SEC"1"
VOLTAGE"4V"
TOLERANCE"20%"
PACK_TYPE"0201"
VALUE"1UF"
MATERIAL"X6S"
CDS_LIB"pure_quanta"
PART_NUMBER"CH-10KMEE00";
"B"
$PN"2"6;
"A"
$PN"1"5;
%"Q_CAP"
"1","(-2600,4475)","0","pure_quanta","I64";
;
LOCATION"C255"
$SEC"1"
CDS_SEC"1"
TOLERANCE"20%"
VOLTAGE"4V"
VALUE"22UF"
PACK_TYPE"C0402"
MATERIAL"X6S"
CDS_LIB"pure_quanta"
PART_NUMBER"CH622KMEB02";
"B"
$PN"2"6;
"A"
$PN"1"5;
%"Q_CAP"
"1","(-2375,4475)","0","pure_quanta","I65";
;
LOCATION"C262"
$SEC"1"
CDS_SEC"1"
VOLTAGE"4V"
VALUE"22UF"
MATERIAL"X6S"
TOLERANCE"20%"
PACK_TYPE"C0402"
CDS_LIB"pure_quanta"
PART_NUMBER"CH622KMEB02";
"B"
$PN"2"6;
"A"
$PN"1"5;
%"Q_CAP"
"1","(-2150,4475)","0","pure_quanta","I66";
;
LOCATION"C259"
$SEC"1"
CDS_SEC"1"
PACK_TYPE"C0402"
MATERIAL"X6S"
TOLERANCE"20%"
VALUE"22UF"
VOLTAGE"4V"
CDS_LIB"pure_quanta"
PART_NUMBER"CH622KMEB02";
"B"
$PN"2"6;
"A"
$PN"1"5;
%"Q_CAP"
"1","(-1850,4475)","0","pure_quanta","I67";
;
LOCATION"C254"
$SEC"1"
CDS_SEC"1"
MATERIAL"X6S"
TOLERANCE"20%"
PACK_TYPE"C0402"
VALUE"10UF"
VOLTAGE"6.3V"
CDS_LIB"pure_quanta"
PART_NUMBER"CH6101MEB01";
"B"
$PN"2"6;
"A"
$PN"1"5;
%"Q_CAP"
"1","(-1550,4475)","0","pure_quanta","I68";
;
LOCATION"C286"
$SEC"1"
CDS_SEC"1"
VALUE"10UF"
MATERIAL"X6S"
VOLTAGE"6.3V"
TOLERANCE"20%"
PACK_TYPE"C0402"
CDS_LIB"pure_quanta"
PART_NUMBER"CH6101MEB01";
"B"
$PN"2"6;
"A"
$PN"1"5;
%"VCC_CORE"
"1","(-3750,5125)","0","pure_quanta_power","I69";
;
HDL_POWER"P0V9_CPU1_RT0_2A"
CDS_LIB"pure_quanta_power";
"A"5;
%"Q_CAP"
"1","(-6850,4475)","0","pure_quanta","I7";
;
LOCATION"C121"
$SEC"1"
CDS_SEC"1"
VOLTAGE"6.3V"
VALUE"4.7UF"
TOLERANCE"20%"
MATERIAL"X6S"
PACK_TYPE"0402"
CDS_LIB"pure_quanta"
PART_NUMBER"CH5471MEB01";
"B"
$PN"2"4;
"A"
$PN"1"3;
%"Q_CAP"
"1","(-3750,3850)","0","pure_quanta","I70";
;
LOCATION"C250"
$SEC"1"
CDS_SEC"1"
TOLERANCE"20%"
MATERIAL"X6S"
PACK_TYPE"C0402"
VOLTAGE"6.3V"
VALUE"10UF"
CDS_LIB"pure_quanta"
PART_NUMBER"CH6101MEB01";
"B"
$PN"2"6;
"A"
$PN"1"5;
%"Q_CAP"
"1","(-3525,3850)","0","pure_quanta","I71";
;
LOCATION"C269"
$SEC"1"
CDS_SEC"1"
PACK_TYPE"C0402"
VOLTAGE"6.3V"
TOLERANCE"20%"
VALUE"10UF"
MATERIAL"X6S"
CDS_LIB"pure_quanta"
PART_NUMBER"CH6101MEB01";
"B"
$PN"2"6;
"A"
$PN"1"5;
%"Q_CAP"
"1","(-3300,3850)","0","pure_quanta","I72";
;
LOCATION"C241"
$SEC"1"
CDS_SEC"1"
VOLTAGE"6.3V"
PACK_TYPE"0402"
MATERIAL"X6S"
TOLERANCE"20%"
VALUE"4.7UF"
CDS_LIB"pure_quanta"
PART_NUMBER"CH5471MEB01";
"B"
$PN"2"6;
"A"
$PN"1"5;
%"Q_CAP"
"1","(-3075,4475)","0","pure_quanta","I73";
;
LOCATION"C247"
$SEC"1"
CDS_SEC"1"
TOLERANCE"20%"
VALUE"100UF"
PACK_TYPE"C0805"
MATERIAL"X6S"
VOLTAGE"4V"
CDS_LIB"pure_quanta"
PART_NUMBER"CH710KMEA01";
"B"
$PN"2"6;
"A"
$PN"1"5;
%"Q_INDUCTOR"
"1","(-4100,4750)","0","pure_quanta","I74";
;
LOCATION"L4"
$SEC"1"
CDS_SEC"1"
MATERIAL"IND"
VALUE"100NH/16A"
PACK_TYPE"SMLF"
NEEDS_NO_SIZE"TRUE"
CDS_LIB"pure_quanta"
PART_NUMBER"CV+10G0MZ04";
"1"
$PN"1"7;
"2"
$PN"2"5;
%"Q_CAP"
"1","(-1400,5700)","0","pure_quanta","I75";
;
LOCATION"C189"
$SEC"1"
CDS_SEC"1"
VALUE"0.1UF"
PACK_TYPE"C0201"
MATERIAL"X7S"
VOLTAGE"10V"
TOLERANCE"10%"
CDS_LIB"pure_quanta"
PART_NUMBER"CH4102K6E00";
"B"
$PN"2"8;
"A"
$PN"1"7;
%"Q_CAP"
"1","(-1675,5700)","0","pure_quanta","I76";
;
LOCATION"C266"
$SEC"1"
CDS_SEC"1"
VALUE"0.1UF"
VOLTAGE"10V"
MATERIAL"X7S"
PACK_TYPE"C0201"
TOLERANCE"10%"
CDS_LIB"pure_quanta"
PART_NUMBER"CH4102K6E00";
"B"
$PN"2"8;
"A"
$PN"1"7;
%"Q_CAP"
"1","(-1925,5700)","0","pure_quanta","I77";
;
LOCATION"C139"
$SEC"1"
CDS_SEC"1"
VOLTAGE"10V"
VALUE"0.1UF"
PACK_TYPE"C0201"
MATERIAL"X7S"
TOLERANCE"10%"
CDS_LIB"pure_quanta"
PART_NUMBER"CH4102K6E00";
"B"
$PN"2"8;
"A"
$PN"1"7;
%"Q_CAP"
"1","(-2200,5700)","0","pure_quanta","I78";
;
LOCATION"C137"
$SEC"1"
CDS_SEC"1"
MATERIAL"X7S"
PACK_TYPE"C0201"
TOLERANCE"10%"
VOLTAGE"10V"
VALUE"0.1UF"
CDS_LIB"pure_quanta"
PART_NUMBER"CH4102K6E00";
"B"
$PN"2"8;
"A"
$PN"1"7;
%"UNIVERSAL_GND"
"1","(-1475,5300)","0","pure_quanta_power","I79";
;
CDS_LIB"pure_quanta_power"
HDL_POWER"GND";
"A"8;
%"Q_CAP"
"1","(-2950,2525)","0","pure_quanta","I80";
;
LOCATION"C282"
$SEC"1"
CDS_SEC"1"
TOLERANCE"10%"
VOLTAGE"10V"
MATERIAL"X7S"
PACK_TYPE"C0201"
VALUE"0.1UF"
CDS_LIB"pure_quanta"
PART_NUMBER"CH4102K6E00";
"B"
$PN"2"9;
"A"
$PN"1"5;
%"Q_CAP"
"1","(-3175,2525)","0","pure_quanta","I81";
;
LOCATION"C264"
$SEC"1"
CDS_SEC"1"
PACK_TYPE"C0201"
VALUE"0.1UF"
MATERIAL"X7S"
TOLERANCE"10%"
VOLTAGE"10V"
CDS_LIB"pure_quanta"
PART_NUMBER"CH4102K6E00";
"B"
$PN"2"9;
"A"
$PN"1"5;
%"Q_CAP"
"1","(-3475,2525)","0","pure_quanta","I82";
;
LOCATION"C141"
$SEC"1"
CDS_SEC"1"
VALUE"0.1UF"
MATERIAL"X7S"
PACK_TYPE"C0201"
VOLTAGE"10V"
TOLERANCE"10%"
CDS_LIB"pure_quanta"
PART_NUMBER"CH4102K6E00";
"B"
$PN"2"9;
"A"
$PN"1"5;
%"Q_CAP"
"1","(-1650,2525)","0","pure_quanta","I83";
;
LOCATION"C192"
$SEC"1"
CDS_SEC"1"
MATERIAL"X7S"
PACK_TYPE"C0201"
TOLERANCE"10%"
VALUE"0.1UF"
VOLTAGE"10V"
CDS_LIB"pure_quanta"
PART_NUMBER"CH4102K6E00";
"B"
$PN"2"9;
"A"
$PN"1"5;
%"Q_CAP"
"1","(-1900,2525)","0","pure_quanta","I84";
;
LOCATION"C260"
$SEC"1"
CDS_SEC"1"
PACK_TYPE"C0201"
MATERIAL"X7S"
VALUE"0.1UF"
VOLTAGE"10V"
TOLERANCE"10%"
CDS_LIB"pure_quanta"
PART_NUMBER"CH4102K6E00";
"B"
$PN"2"9;
"A"
$PN"1"5;
%"Q_CAP"
"1","(-2175,2525)","0","pure_quanta","I85";
;
LOCATION"C184"
$SEC"1"
CDS_SEC"1"
PACK_TYPE"C0201"
MATERIAL"X7S"
VOLTAGE"10V"
TOLERANCE"10%"
VALUE"0.1UF"
CDS_LIB"pure_quanta"
PART_NUMBER"CH4102K6E00";
"B"
$PN"2"9;
"A"
$PN"1"5;
%"Q_CAP"
"1","(-2450,2525)","0","pure_quanta","I86";
;
LOCATION"C253"
$SEC"1"
CDS_SEC"1"
VALUE"0.1UF"
TOLERANCE"10%"
VOLTAGE"10V"
MATERIAL"X7S"
PACK_TYPE"C0201"
CDS_LIB"pure_quanta"
PART_NUMBER"CH4102K6E00";
"B"
$PN"2"9;
"A"
$PN"1"5;
%"Q_CAP"
"1","(-2700,2525)","0","pure_quanta","I87";
;
LOCATION"C228"
$SEC"1"
CDS_SEC"1"
PACK_TYPE"C0201"
MATERIAL"X7S"
VALUE"0.1UF"
VOLTAGE"10V"
TOLERANCE"10%"
CDS_LIB"pure_quanta"
PART_NUMBER"CH4102K6E00";
"B"
$PN"2"9;
"A"
$PN"1"5;
%"UNIVERSAL_GND"
"1","(-1650,2100)","0","pure_quanta_power","I88";
;
CDS_LIB"pure_quanta_power"
HDL_POWER"GND";
"A"9;
%"VCC_CORE"
"1","(-3425,1950)","0","pure_quanta_power","I89";
;
HDL_POWER"P0V9_CPU1_RT0_2A_2D"
CDS_LIB"pure_quanta_power";
"A"11;
%"Q_CAP"
"1","(-6425,4475)","0","pure_quanta","I9";
;
LOCATION"C126"
$SEC"1"
CDS_SEC"1"
TOLERANCE"20%"
VOLTAGE"4V"
MATERIAL"X6S"
PACK_TYPE"0201"
VALUE"1UF"
CDS_LIB"pure_quanta"
PART_NUMBER"CH-10KMEE00";
"B"
$PN"2"4;
"A"
$PN"1"3;
%"UNIVERSAL_GND"
"1","(-2600,1100)","0","pure_quanta_power","I91";
;
CDS_LIB"pure_quanta_power"
HDL_POWER"GND";
"A"10;
%"Q_CAP"
"1","(-2750,1425)","0","pure_quanta","I92";
;
LOCATION"C198"
$SEC"1"
CDS_SEC"1"
TOLERANCE"10%"
MATERIAL"X7S"
VALUE"0.1UF"
PACK_TYPE"C0201"
VOLTAGE"10V"
CDS_LIB"pure_quanta"
PART_NUMBER"CH4102K6E00";
"B"
$PN"2"10;
"A"
$PN"1"11;
%"Q_CAP"
"1","(-3050,1425)","0","pure_quanta","I93";
;
LOCATION"C191"
$SEC"1"
CDS_SEC"1"
VALUE"0.1UF"
VOLTAGE"10V"
PACK_TYPE"C0201"
MATERIAL"X7S"
TOLERANCE"10%"
CDS_LIB"pure_quanta"
PART_NUMBER"CH4102K6E00";
"B"
$PN"2"10;
"A"
$PN"1"11;
%"Q_RES"
"1","(-4200,2775)","0","pure_quanta","I95";
;
LOCATION"R6705"
$SEC"1"
CDS_SEC"1"
PACK_TYPE"0603LF"
WATTAGE"1/4W"
TOLERANCE"5%"
VALUE"0"
MATERIAL"CHIP"
CDS_LIB"pure_quanta"
PART_NUMBER"CS00006J900";
"B"
$PN"2"5;
"A"
$PN"1"11;
%"Q_RES"
"2","(-4575,3050)","2","pure_quanta","I96";
;
LOCATION"R6704"
$SEC"1"
CDS_SEC"1"
MATERIAL"EMPTY"
PACK_TYPE"0603LF"
VALUE"0"
WATTAGE"1/4W"
TOLERANCE"5%"
CDS_LIB"pure_quanta"
PART_NUMBER"CS00006J900";
"A"
$PN"1"7;
"B"
$PN"2"11;
%"Q_INDUCTOR"
"1","(-8500,4400)","3","pure_quanta","I97";
;
LOCATION"L27"
$SEC"1"
CDS_SEC"1"
MATERIAL"IND"
VALUE"BLM15PD121SN1D/1300MA"
PACK_TYPE"SMLF"
NEEDS_NO_SIZE"TRUE"
CDS_LIB"pure_quanta"
PART_NUMBER"CX5PD121000";
"1"
$PN"1"1;
"2"
$PN"2"12;
%"Q_RES"
"2","(-8375,4375)","0","pure_quanta","I98";
;
LOCATION"R6701"
$SEC"1"
CDS_SEC"1"
VALUE"0"
PACK_TYPE"0402LF"
MATERIAL"EMPTY"
TOLERANCE"5%"
WATTAGE"1/16W"
CDS_LIB"pure_quanta"
PART_NUMBER"CS00002JB13";
"A"
$PN"1"1;
"B"
$PN"2"12;
%"Q_CAP"
"1","(-3300,1425)","0","pure_quanta","I99";
;
LOCATION"C187"
$SEC"1"
CDS_SEC"1"
VALUE"1UF"
PACK_TYPE"0201"
MATERIAL"X6S"
TOLERANCE"20%"
VOLTAGE"4V"
CDS_LIB"pure_quanta"
PART_NUMBER"CH-10KMEE00";
"B"
$PN"2"10;
"A"
$PN"1"11;
END.
